(kicad_pcb
	(version 20241229)
	(generator "pcbnew")
	(generator_version "9.0")
	(general
		(thickness 1.62)
		(legacy_teardrops no)
	)
	(paper "A4")
	(title_block
		(title "OCuLink to 10GbE adapter")
		(date "2026-02-23")
		(rev "1.1.0")
		(company "Antmicro Ltd")
		(comment 1 "www.antmicro.com")
		(comment 9 "footprints 73-77 of 510")
	)
	(layers
		(0 "F.Cu" signal)
		(4 "In1.Cu" signal)
		(6 "In2.Cu" signal)
		(8 "In3.Cu" signal)
		(10 "In4.Cu" signal)
		(12 "In5.Cu" signal)
		(14 "In6.Cu" signal)
		(2 "B.Cu" signal)
		(9 "F.Adhes" user "F.Adhesive")
		(11 "B.Adhes" user "B.Adhesive")
		(13 "F.Paste" user)
		(15 "B.Paste" user)
		(5 "F.SilkS" user "F.Silkscreen")
		(7 "B.SilkS" user "B.Silkscreen")
		(1 "F.Mask" user)
		(3 "B.Mask" user)
		(17 "Dwgs.User" user "User.Drawings")
		(19 "Cmts.User" user "User.Comments")
		(21 "Eco1.User" user "User.Eco1")
		(23 "Eco2.User" user "User.Eco2")
		(25 "Edge.Cuts" user)
		(27 "Margin" user)
		(31 "F.CrtYd" user "F.Courtyard")
		(29 "B.CrtYd" user "B.Courtyard")
		(35 "F.Fab" user)
		(33 "B.Fab" user)
	)
	(footprint "antmicro-footprints:C_0402_1005Metric"
		(layer "F.Cu")
		(at 67.9 103.7 90)
		(descr "Capacitor SMD 0402")
		(tags "capacitor SMD 0402")
		(property "Reference" "C185"
			(at -1.48 -0.59 90)
			(layer "F.SilkS")
			(effects
				(font
					(size 0.7 0.7)
					(thickness 0.15)
				)
				(justify left bottom)
			)
		)
		(property "Value" "C_100n_0402"
			(at -1.022927 2.155213 90)
			(layer "F.Fab")
			(hide yes)
			(effects
				(font
					(size 0.7 0.7)
					(thickness 0.15)
				)
				(justify left bottom)
			)
		)
		(property "Datasheet" "https://www.murata.com/products/productdetail?partno=GRM155R61H104KE14%23"
			(at 0 0 90)
			(layer "F.Fab")
			(hide yes)
			(effects
				(font
					(size 1.27 1.27)
					(thickness 0.15)
				)
			)
		)
		(property "Description" "SMD Multilayer Ceramic Capacitor, 0.1 µF, 50 V, 0402 [1005 Metric], ± 10%, X5R, GRM Series"
			(at 0 0 90)
			(layer "F.Fab")
			(hide yes)
			(effects
				(font
					(size 1.27 1.27)
					(thickness 0.15)
				)
			)
		)
		(property "MPN" "GRM155R61H104KE14D"
			(at 0 0 90)
			(unlocked yes)
			(layer "F.Fab")
			(hide yes)
			(effects
				(font
					(size 1 1)
					(thickness 0.15)
				)
			)
		)
		(property "Val" "100n"
			(at 0 0 90)
			(unlocked yes)
			(layer "F.Fab")
			(hide yes)
			(effects
				(font
					(size 1 1)
					(thickness 0.15)
				)
			)
		)
		(property "Voltage" "50V"
			(at 0 0 90)
			(unlocked yes)
			(layer "F.Fab")
			(hide yes)
			(effects
				(font
					(size 1 1)
					(thickness 0.15)
				)
			)
		)
		(property "Dielectric" "X5R"
			(at 0 0 90)
			(unlocked yes)
			(layer "F.Fab")
			(hide yes)
			(effects
				(font
					(size 1 1)
					(thickness 0.15)
				)
			)
		)
		(property "Manufacturer" "Murata"
			(at 0 0 90)
			(unlocked yes)
			(layer "F.Fab")
			(hide yes)
			(effects
				(font
					(size 1 1)
					(thickness 0.15)
				)
			)
		)
		(property "License" "Apache-2.0"
			(at 0 0 90)
			(unlocked yes)
			(layer "F.Fab")
			(hide yes)
			(effects
				(font
					(size 1 1)
					(thickness 0.15)
				)
			)
		)
		(property "Author" "Antmicro"
			(at 0 0 90)
			(unlocked yes)
			(layer "F.Fab")
			(hide yes)
			(effects
				(font
					(size 1 1)
					(thickness 0.15)
				)
			)
		)
		(sheetname "/X710-AT2 power/")
		(sheetfile "x710-at2-power.kicad_sch")
		(attr smd)
		(fp_rect
			(start -0.925 -0.47)
			(end 0.925 0.47)
			(stroke
				(width 0.05)
				(type default)
			)
			(fill no)
			(layer "F.CrtYd")
		)
		(fp_line
			(start 0.504 -0.25)
			(end 0.504 0.248)
			(stroke
				(width 0.15)
				(type solid)
			)
			(layer "F.Fab")
		)
		(fp_line
			(start -0.494 -0.25)
			(end 0.504 -0.25)
			(stroke
				(width 0.15)
				(type solid)
			)
			(layer "F.Fab")
		)
		(fp_line
			(start 0.504 0.248)
			(end -0.494 0.248)
			(stroke
				(width 0.15)
				(type solid)
			)
			(layer "F.Fab")
		)
		(fp_line
			(start -0.494 0.248)
			(end -0.494 -0.25)
			(stroke
				(width 0.15)
				(type solid)
			)
			(layer "F.Fab")
		)
		(pad "1" smd roundrect
			(at -0.48 0 90)
			(size 0.59 0.64)
			(layers "F.Cu" "F.Mask" "F.Paste")
			(roundrect_rratio 0.25)
			(net 28 "GND")
			(pintype "passive")
		)
		(pad "2" smd roundrect
			(at 0.48 0 90)
			(size 0.59 0.64)
			(layers "F.Cu" "F.Mask" "F.Paste")
			(roundrect_rratio 0.25)
			(net 302 "+1V0")
			(pintype "passive")
		)
	)
	(footprint "antmicro-footprints:C_0402_1005Metric"
		(layer "F.Cu")
		(at 69.52 107.94)
		(descr "Capacitor SMD 0402")
		(tags "capacitor SMD 0402")
		(property "Reference" "C72"
			(at -2.85 0.46 0)
			(layer "F.SilkS")
			(effects
				(font
					(size 0.7 0.7)
					(thickness 0.15)
				)
				(justify left bottom)
			)
		)
		(property "Value" "C_5p6_0402"
			(at -1.022927 2.155213 0)
			(layer "F.Fab")
			(hide yes)
			(effects
				(font
					(size 0.7 0.7)
					(thickness 0.15)
				)
				(justify left bottom)
			)
		)
		(property "Datasheet" "https://www.mouser.com/datasheet/3/76/2/GCM1555C1H5R6BA16_01A.pdf"
			(at 0 0 0)
			(layer "F.Fab")
			(hide yes)
			(effects
				(font
					(size 1.27 1.27)
					(thickness 0.15)
				)
			)
		)
		(property "Description" "Multilayer Ceramic Capacitors MLCC - SMD/SMT 5.6 pF 50 VDC 0.1 pF 0402 C0G (NP0) AEC-Q200"
			(at 0 0 0)
			(layer "F.Fab")
			(hide yes)
			(effects
				(font
					(size 1.27 1.27)
					(thickness 0.15)
				)
			)
		)
		(property "MPN" "GCM1555C1H5R6BA16D"
			(at 0 0 0)
			(unlocked yes)
			(layer "F.Fab")
			(hide yes)
			(effects
				(font
					(size 1 1)
					(thickness 0.15)
				)
			)
		)
		(property "Manufacturer" "Murata"
			(at 0 0 0)
			(unlocked yes)
			(layer "F.Fab")
			(hide yes)
			(effects
				(font
					(size 1 1)
					(thickness 0.15)
				)
			)
		)
		(property "License" "Apache-2.0"
			(at 0 0 0)
			(unlocked yes)
			(layer "F.Fab")
			(hide yes)
			(effects
				(font
					(size 1 1)
					(thickness 0.15)
				)
			)
		)
		(property "Author" "Antmicro"
			(at 0 0 0)
			(unlocked yes)
			(layer "F.Fab")
			(hide yes)
			(effects
				(font
					(size 1 1)
					(thickness 0.15)
				)
			)
		)
		(property "Val" "5p6"
			(at 0 0 0)
			(unlocked yes)
			(layer "F.Fab")
			(hide yes)
			(effects
				(font
					(size 1 1)
					(thickness 0.15)
				)
			)
		)
		(property "Voltage" "50V"
			(at 0 0 0)
			(unlocked yes)
			(layer "F.Fab")
			(hide yes)
			(effects
				(font
					(size 1 1)
					(thickness 0.15)
				)
			)
		)
		(property "Dielectric" "C0G"
			(at 0 0 0)
			(unlocked yes)
			(layer "F.Fab")
			(hide yes)
			(effects
				(font
					(size 1 1)
					(thickness 0.15)
				)
			)
		)
		(sheetname "/X710-AT2 Misc/")
		(sheetfile "x710-at2-mics.kicad_sch")
		(attr smd)
		(fp_rect
			(start -0.925 -0.47)
			(end 0.925 0.47)
			(stroke
				(width 0.05)
				(type default)
			)
			(fill no)
			(layer "F.CrtYd")
		)
		(fp_line
			(start -0.494 -0.25)
			(end 0.504 -0.25)
			(stroke
				(width 0.15)
				(type solid)
			)
			(layer "F.Fab")
		)
		(fp_line
			(start -0.494 0.248)
			(end -0.494 -0.25)
			(stroke
				(width 0.15)
				(type solid)
			)
			(layer "F.Fab")
		)
		(fp_line
			(start 0.504 -0.25)
			(end 0.504 0.248)
			(stroke
				(width 0.15)
				(type solid)
			)
			(layer "F.Fab")
		)
		(fp_line
			(start 0.504 0.248)
			(end -0.494 0.248)
			(stroke
				(width 0.15)
				(type solid)
			)
			(layer "F.Fab")
		)
		(pad "1" smd roundrect
			(at -0.48 0)
			(size 0.59 0.64)
			(layers "F.Cu" "F.Mask" "F.Paste")
			(roundrect_rratio 0.25)
			(net 28 "GND")
			(pintype "passive")
		)
		(pad "2" smd roundrect
			(at 0.48 0)
			(size 0.59 0.64)
			(layers "F.Cu" "F.Mask" "F.Paste")
			(roundrect_rratio 0.25)
			(net 76 "/X710-AT2 Misc/50MHZ_XTAL_R.+")
			(pintype "passive")
		)
	)
	(footprint "antmicro-footprints:VQFN-HR-9_2x1.5mm"
		(layer "F.Cu")
		(at 70.95 80.039996 180)
		(property "Reference" "U1"
			(at -2.11 -0.130004 90)
			(layer "F.SilkS")
			(effects
				(font
					(size 0.7 0.7)
					(thickness 0.15)
				)
				(justify left bottom)
			)
		)
		(property "Value" "TPS566231P"
			(at -1.45 2.45 0)
			(layer "F.Fab")
			(hide yes)
			(effects
				(font
					(size 0.7 0.7)
					(thickness 0.15)
				)
				(justify right top)
			)
		)
		(property "Datasheet" "https://www.ti.com/lit/ds/symlink/tps566231.pdf"
			(at 0 -0.045 0)
			(layer "F.Fab")
			(hide yes)
			(effects
				(font
					(size 0.7 0.7)
					(thickness 0.15)
				)
				(justify right top)
			)
		)
		(property "Description" "Switching Voltage Regulators 3-V to 18-V, 6-A synchronous buck converter"
			(at -1.45 3.65 0)
			(layer "F.Fab")
			(hide yes)
			(effects
				(font
					(size 0.7 0.7)
					(thickness 0.15)
				)
				(justify right top)
			)
		)
		(property "Manufacturer" "Texas Instruments"
			(at 0 0 180)
			(unlocked yes)
			(layer "F.Fab")
			(hide yes)
			(effects
				(font
					(size 1 1)
					(thickness 0.15)
				)
			)
		)
		(property "MPN" "TPS566231PRQFR"
			(at 0 0 180)
			(unlocked yes)
			(layer "F.Fab")
			(hide yes)
			(effects
				(font
					(size 1 1)
					(thickness 0.15)
				)
			)
		)
		(property "Author" "Antmicro"
			(at 0 0 180)
			(unlocked yes)
			(layer "F.Fab")
			(hide yes)
			(effects
				(font
					(size 1 1)
					(thickness 0.15)
				)
			)
		)
		(property "License" "Apache-2.0"
			(at 0 0 180)
			(unlocked yes)
			(layer "F.Fab")
			(hide yes)
			(effects
				(font
					(size 1 1)
					(thickness 0.15)
				)
			)
		)
		(sheetname "/Power/")
		(sheetfile "power.kicad_sch")
		(attr smd)
		(fp_line
			(start 1 0.945)
			(end 0.2 0.945)
			(stroke
				(width 0.15)
				(type solid)
			)
			(layer "F.SilkS")
		)
		(fp_line
			(start 1 -0.945)
			(end 0.695 -0.945)
			(stroke
				(width 0.15)
				(type solid)
			)
			(layer "F.SilkS")
		)
		(fp_line
			(start -1 0.945)
			(end -0.695 0.945)
			(stroke
				(width 0.15)
				(type solid)
			)
			(layer "F.SilkS")
		)
		(fp_line
			(start -1 -0.945)
			(end -0.695 -0.945)
			(stroke
				(width 0.15)
				(type solid)
			)
			(layer "F.SilkS")
		)
		(fp_circle
			(center -1.18 -0.77)
			(end -1.13 -0.77)
			(stroke
				(width 0.15)
				(type solid)
			)
			(fill yes)
			(layer "F.SilkS")
		)
		(fp_rect
			(start -1.3 -1.05)
			(end 1.3 1.05)
			(stroke
				(width 0.05)
				(type solid)
			)
			(fill no)
			(layer "F.CrtYd")
		)
		(fp_rect
			(start -1 -0.75)
			(end 1 0.75)
			(stroke
				(width 0.15)
				(type solid)
			)
			(fill no)
			(layer "F.Fab")
		)
		(pad "1" smd roundrect
			(at -0.925 -0.5 180)
			(size 0.55 0.25)
			(layers "F.Cu" "F.Mask" "F.Paste")
			(roundrect_rratio 0.125)
			(net 315 "/Power/3V3_VCC")
			(pinfunction "V_{CC}")
			(pintype "passive")
		)
		(pad "2" smd roundrect
			(at -0.925 0 180)
			(size 0.55 0.25)
			(layers "F.Cu" "F.Mask" "F.Paste")
			(roundrect_rratio 0.125)
			(net 317 "/Power/3V3_FB")
			(pinfunction "FB")
			(pintype "input")
		)
		(pad "3" smd roundrect
			(at -0.925 0.5 180)
			(size 0.55 0.25)
			(layers "F.Cu" "F.Mask" "F.Paste")
			(roundrect_rratio 0.125)
			(net 379 "/Power/3V3_EN")
			(pinfunction "EN")
			(pintype "input")
		)
		(pad "4" smd roundrect
			(at -0.25 0.45 180)
			(size 0.25 1)
			(layers "F.Cu" "F.Mask" "F.Paste")
			(roundrect_rratio 0.125)
			(net 28 "GND")
			(pinfunction "PGND")
			(pintype "power_in")
		)
		(pad "5" smd roundrect
			(at 0.925 0.5 180)
			(size 0.55 0.25)
			(layers "F.Cu" "F.Mask" "F.Paste")
			(roundrect_rratio 0.125)
			(net 314 "VCC")
			(pinfunction "V_{IN}")
			(pintype "power_in")
		)
		(pad "6" smd roundrect
			(at 0.925 0 180)
			(size 0.55 0.25)
			(layers "F.Cu" "F.Mask" "F.Paste")
			(roundrect_rratio 0.125)
			(net 314 "VCC")
			(pinfunction "V_{IN}")
			(pintype "passive")
		)
		(pad "7" smd roundrect
			(at 0.925 -0.5 180)
			(size 0.55 0.25)
			(layers "F.Cu" "F.Mask" "F.Paste")
			(roundrect_rratio 0.125)
			(net 316 "/Power/3V3_BST")
			(pinfunction "BST")
			(pintype "passive")
		)
		(pad "8" smd roundrect
			(at 0.25 -0.3 180)
			(size 0.25 1.3)
			(layers "F.Cu" "F.Mask" "F.Paste")
			(roundrect_rratio 0.125)
			(net 333 "/Power/3V3_SW")
			(pinfunction "SW")
			(pintype "power_out")
		)
		(pad "9" smd roundrect
			(at -0.25 -0.675 180)
			(size 0.25 0.55)
			(layers "F.Cu" "F.Mask" "F.Paste")
			(roundrect_rratio 0.125)
			(net 338 "/Power/3V3_PG")
			(pinfunction "PG")
			(pintype "passive")
		)
	)
	(footprint "antmicro-footprints:R_0402_1005Metric"
		(layer "F.Cu")
		(at 72.42 107.35)
		(descr "Resistor SMD 0402")
		(tags "resistor SMD 0402")
		(property "Reference" "R47"
			(at -0.9 1.23 0)
			(layer "F.SilkS")
			(effects
				(font
					(size 0.7 0.7)
					(thickness 0.15)
				)
				(justify left bottom)
			)
		)
		(property "Value" "R_10R_0402"
			(at -1.011843 1.772047 0)
			(layer "F.Fab")
			(hide yes)
			(effects
				(font
					(size 0.7 0.7)
					(thickness 0.15)
				)
				(justify left bottom)
			)
		)
		(property "Datasheet" "https://www.bourns.com/docs/product-datasheets/cr.pdf"
			(at 0 0 0)
			(layer "F.Fab")
			(hide yes)
			(effects
				(font
					(size 1.27 1.27)
					(thickness 0.15)
				)
			)
		)
		(property "Description" "SMD Chip Resistor, 10 ohm, ± 1%, 62.5 mW, 0402 [1005 Metric], Thick Film, General Purpose"
			(at 0 0 0)
			(layer "F.Fab")
			(hide yes)
			(effects
				(font
					(size 1.27 1.27)
					(thickness 0.15)
				)
			)
		)
		(property "MPN" "CR0402-FX-10R0GLF"
			(at 0 0 0)
			(unlocked yes)
			(layer "F.Fab")
			(hide yes)
			(effects
				(font
					(size 1 1)
					(thickness 0.15)
				)
			)
		)
		(property "Manufacturer" "Bourns"
			(at 0 0 0)
			(unlocked yes)
			(layer "F.Fab")
			(hide yes)
			(effects
				(font
					(size 1 1)
					(thickness 0.15)
				)
			)
		)
		(property "License" "Apache-2.0"
			(at 0 0 0)
			(unlocked yes)
			(layer "F.Fab")
			(hide yes)
			(effects
				(font
					(size 1 1)
					(thickness 0.15)
				)
			)
		)
		(property "Author" "Antmicro"
			(at 0 0 0)
			(unlocked yes)
			(layer "F.Fab")
			(hide yes)
			(effects
				(font
					(size 1 1)
					(thickness 0.15)
				)
			)
		)
		(property "Val" "10R"
			(at 0 0 0)
			(unlocked yes)
			(layer "F.Fab")
			(hide yes)
			(effects
				(font
					(size 1 1)
					(thickness 0.15)
				)
			)
		)
		(property "Tolerance" "1%"
			(at 0 0 0)
			(unlocked yes)
			(layer "F.Fab")
			(hide yes)
			(effects
				(font
					(size 1 1)
					(thickness 0.15)
				)
			)
		)
		(sheetname "/X710-AT2 Misc/")
		(sheetfile "x710-at2-mics.kicad_sch")
		(attr smd)
		(fp_rect
			(start -0.925 -0.47)
			(end 0.925 0.47)
			(stroke
				(width 0.05)
				(type default)
			)
			(fill no)
			(layer "F.CrtYd")
		)
		(fp_rect
			(start -0.5 -0.25)
			(end 0.5 0.25)
			(stroke
				(width 0.15)
				(type solid)
			)
			(fill no)
			(layer "F.Fab")
		)
		(pad "1" smd roundrect
			(at -0.48 0)
			(size 0.59 0.64)
			(layers "F.Cu" "F.Mask" "F.Paste")
			(roundrect_rratio 0.25)
			(net 76 "/X710-AT2 Misc/50MHZ_XTAL_R.+")
			(pintype "passive")
		)
		(pad "2" smd roundrect
			(at 0.48 0)
			(size 0.59 0.64)
			(layers "F.Cu" "F.Mask" "F.Paste")
			(roundrect_rratio 0.25)
			(net 153 "/X710-AT2 Misc/50MHZ_XTAL.+")
			(pintype "passive")
		)
	)
	(footprint "antmicro-footprints:R_0603_1608Metric"
		(layer "F.Cu")
		(at 74.899998 86.459997 -90)
		(descr "Resistor SMD 0603")
		(tags "resistor SMD 0603")
		(property "Reference" "R1"
			(at 0.950003 0.149998 90)
			(layer "F.SilkS")
			(effects
				(font
					(size 0.7 0.7)
					(thickness 0.15)
				)
				(justify right top)
			)
		)
		(property "Value" "R_0R_22.4A_0603"
			(at 0 1.6 90)
			(layer "F.Fab")
			(hide yes)
			(effects
				(font
					(size 0.7 0.7)
					(thickness 0.15)
				)
				(justify right top)
			)
		)
		(property "Datasheet" "https://fscdn.rohm.com/en/products/databook/datasheet/passive/resistor/chip_resistor/pmr-jpw-e.pdf"
			(at 0 0 90)
			(layer "F.Fab")
			(hide yes)
			(effects
				(font
					(size 1.27 1.27)
					(thickness 0.15)
				)
			)
		)
		(property "Description" "SMD Chip Resistor"
			(at 0 0 90)
			(layer "F.Fab")
			(hide yes)
			(effects
				(font
					(size 1.27 1.27)
					(thickness 0.15)
				)
			)
		)
		(property "MPN" "PMR03EZPJ000"
			(at 0 0 270)
			(unlocked yes)
			(layer "F.Fab")
			(hide yes)
			(effects
				(font
					(size 1 1)
					(thickness 0.15)
				)
			)
		)
		(property "Manufacturer" "ROHM Semiconductor"
			(at 0 0 270)
			(unlocked yes)
			(layer "F.Fab")
			(hide yes)
			(effects
				(font
					(size 1 1)
					(thickness 0.15)
				)
			)
		)
		(property "Val" "0R"
			(at 0 0 270)
			(unlocked yes)
			(layer "F.Fab")
			(hide yes)
			(effects
				(font
					(size 1 1)
					(thickness 0.15)
				)
			)
		)
		(property "Max. Curr." "22.4A"
			(at 0 0 270)
			(unlocked yes)
			(layer "F.Fab")
			(hide yes)
			(effects
				(font
					(size 1 1)
					(thickness 0.15)
				)
			)
		)
		(property "Author" "Antmicro"
			(at 0 0 270)
			(unlocked yes)
			(layer "F.Fab")
			(hide yes)
			(effects
				(font
					(size 1 1)
					(thickness 0.15)
				)
			)
		)
		(property "License" "Apache-2.0"
			(at 0 0 270)
			(unlocked yes)
			(layer "F.Fab")
			(hide yes)
			(effects
				(font
					(size 1 1)
					(thickness 0.15)
				)
			)
		)
		(property "Tolerance" "template_tolerance"
			(at 0 0 270)
			(unlocked yes)
			(layer "F.Fab")
			(hide yes)
			(effects
				(font
					(size 1 1)
					(thickness 0.15)
				)
			)
		)
		(sheetname "/Power/")
		(sheetfile "power.kicad_sch")
		(attr smd)
		(fp_line
			(start -0.15 0.4)
			(end 0.15 0.4)
			(stroke
				(width 0.15)
				(type solid)
			)
			(layer "F.SilkS")
		)
		(fp_line
			(start -0.15 -0.4)
			(end 0.15 -0.4)
			(stroke
				(width 0.15)
				(type solid)
			)
			(layer "F.SilkS")
		)
		(fp_rect
			(start -1.25 -0.65)
			(end 1.25 0.65)
			(stroke
				(width 0.05)
				(type solid)
			)
			(fill no)
			(layer "F.CrtYd")
		)
		(fp_rect
			(start -0.8 -0.4)
			(end 0.8 0.4)
			(stroke
				(width 0.15)
				(type solid)
			)
			(fill no)
			(layer "F.Fab")
		)
		(pad "1" smd roundrect
			(at -0.7 0 270)
			(size 0.8 1)
			(layers "F.Cu" "F.Mask" "F.Paste")
			(roundrect_rratio 0.2)
			(net 255 "/Power/+3V3_OUT")
			(pintype "passive")
		)
		(pad "2" smd roundrect
			(at 0.7 0 270)
			(size 0.8 1)
			(layers "F.Cu" "F.Mask" "F.Paste")
			(roundrect_rratio 0.2)
			(net 7 "+3V3")
			(pintype "passive")
		)
	)
)
